(kicad_pcb
	(version 20260206)
	(generator "pcbnew")
	(generator_version "10.0")
	(general
		(thickness 1.6)
		(legacy_teardrops no)
	)
	(paper "A4")
	(title_block
		(title "Wiwynn_Tioga_Pass_MB.brd")
		(comment 1 "Tioga Pass / footprints 688-694 of 4770")
	)
	(layers
		(0 "F.Cu" signal "TOP")
		(4 "In1.Cu" signal "L2GND")
		(6 "In2.Cu" signal "L3")
		(8 "In3.Cu" signal "L4GND")
		(10 "In4.Cu" signal "L5")
		(12 "In5.Cu" signal "L6GND")
		(14 "In6.Cu" signal "L7VCC")
		(16 "In7.Cu" signal "L8VCC")
		(18 "In8.Cu" signal "L9GND")
		(20 "In9.Cu" signal "L10")
		(22 "In10.Cu" signal "L11GND")
		(24 "In11.Cu" signal "L12")
		(26 "In12.Cu" signal "L13GND")
		(2 "B.Cu" signal "BOTTOM")
		(9 "F.Adhes" user "F.Adhesive")
		(11 "B.Adhes" user "B.Adhesive")
		(13 "F.Paste" user "Package Geometry/Pastemask Top")
		(15 "B.Paste" user "Package Geometry/Pastemask Bottom")
		(5 "F.SilkS" user "Ref Des/Silkscreen Top")
		(7 "B.SilkS" user "Ref Des/Silkscreen Bottom")
		(1 "F.Mask" user "Board Geometry/Soldermask Top")
		(3 "B.Mask" user "Board Geometry/Soldermask Bottom")
		(17 "Dwgs.User" user "User.Drawings")
		(19 "Cmts.User" user "User.Comments")
		(21 "Eco1.User" user "User.Eco1")
		(23 "Eco2.User" user "User.Eco2")
		(25 "Edge.Cuts" user "Board Geometry/Outline")
		(27 "Margin" user)
		(31 "F.CrtYd" user "Package Geometry/Place Bound Top")
		(29 "B.CrtYd" user "Package Geometry/Place Bound Bottom")
		(35 "F.Fab" user "Ref Des/Assembly Top")
		(33 "B.Fab" user "Ref Des/Assembly Bottom")
	)
	(footprint ""
		(layer "F.Cu")
		(at 487.554016 -146.508978 -90)
		(property "Reference" "S9A2"
			(at 1.282446 -2.299208 270)
			(unlocked yes)
			(layer "F.SilkS")
			(effects
				(font
					(size 1.778 2.032)
					(thickness 0.1524)
				)
				(justify left)
			)
		)
		(property "Value" ""
			(at 0 0 270)
			(layer "F.Fab")
			(effects
				(font
					(size 1.27 1.27)
				)
			)
		)
		(duplicate_pad_numbers_are_jumpers no)
		(fp_line
			(start 1.800098 5.3721)
			(end 3.022092 5.3721)
			(stroke
				(width 0.1524)
				(type default)
			)
			(layer "F.SilkS")
		)
		(fp_line
			(start -0.7112 0.978154)
			(end -0.7112 3.52044)
			(stroke
				(width 0.1524)
				(type default)
			)
			(layer "F.SilkS")
		)
		(fp_line
			(start 5.5372 0.973836)
			(end 5.5372 3.52044)
			(stroke
				(width 0.1524)
				(type default)
			)
			(layer "F.SilkS")
		)
		(fp_line
			(start 3.024632 -0.8763)
			(end 1.800098 -0.8763)
			(stroke
				(width 0.1524)
				(type default)
			)
			(layer "F.SilkS")
		)
		(fp_circle
			(center -1.972818 -0.651002)
			(end -1.972818 -0.778002)
			(stroke
				(width 0.254)
				(type default)
			)
			(fill no)
			(layer "F.SilkS")
		)
		(fp_rect
			(start -0.7112 5.3721)
			(end 5.5372 -0.8763)
			(stroke
				(width 0)
				(type default)
			)
			(fill no)
			(layer "F.CrtYd")
		)
		(fp_line
			(start -0.7112 5.3721)
			(end -0.7112 -0.8763)
			(stroke
				(width 0.1)
				(type default)
			)
			(layer "F.Fab")
		)
		(fp_line
			(start 5.5372 5.3721)
			(end -0.7112 5.3721)
			(stroke
				(width 0.1)
				(type default)
			)
			(layer "F.Fab")
		)
		(fp_line
			(start -0.7112 -0.8763)
			(end 5.5372 -0.8763)
			(stroke
				(width 0.1)
				(type default)
			)
			(layer "F.Fab")
		)
		(fp_line
			(start 5.5372 -0.8763)
			(end 5.5372 5.3721)
			(stroke
				(width 0.1)
				(type default)
			)
			(layer "F.Fab")
		)
		(fp_circle
			(center -1.972818 -0.651002)
			(end -1.972818 -0.778002)
			(stroke
				(width 0.254)
				(type default)
			)
			(fill no)
			(layer "F.Fab")
		)
		(fp_text user "4"
			(at 7.040372 6.11124 0)
			(unlocked yes)
			(layer "F.SilkS")
			(effects
				(font
					(size 0.7874 0.5842)
					(thickness 0.1524)
				)
				(justify left)
			)
		)
		(fp_text user "3"
			(at -0.055372 6.018276 0)
			(unlocked yes)
			(layer "F.SilkS")
			(effects
				(font
					(size 0.7874 0.5842)
					(thickness 0.1524)
				)
				(justify left)
			)
		)
		(fp_text user "2"
			(at 5.997448 -1.599184 0)
			(unlocked yes)
			(layer "F.SilkS")
			(effects
				(font
					(size 0.7874 0.5842)
					(thickness 0.1524)
				)
				(justify left)
			)
		)
		(fp_text user "3"
			(at -1.454404 3.553206 0)
			(unlocked yes)
			(layer "F.Fab")
			(effects
				(font
					(size 0.7874 0.5842)
					(thickness 0.1524)
				)
				(justify left)
			)
		)
		(fp_text user "4"
			(at -1.422908 1.380998 0)
			(unlocked yes)
			(layer "F.Fab")
			(effects
				(font
					(size 0.7874 0.5842)
					(thickness 0.1524)
				)
				(justify left)
			)
		)
		(fp_text user "2"
			(at 5.080508 -0.918972 0)
			(unlocked yes)
			(layer "F.Fab")
			(effects
				(font
					(size 0.7874 0.5842)
					(thickness 0.1524)
				)
				(justify left)
			)
		)
		(pad "1" smd rect
			(at 0 0 270)
			(size 2.921 1.27)
			(layers "F.Cu" "F.Mask" "F.Paste")
			(net "GND")
		)
		(pad "2" smd rect
			(at 4.826 0 270)
			(size 2.921 1.27)
			(layers "F.Cu" "F.Mask" "F.Paste")
			(net "GND")
		)
		(pad "3" smd rect
			(at 0 4.4958 270)
			(size 2.921 1.27)
			(layers "F.Cu" "F.Mask" "F.Paste")
			(net "FP_PWR_BTN_R_N")
		)
		(pad "4" smd rect
			(at 4.826 4.4958 270)
			(size 2.921 1.27)
			(layers "F.Cu" "F.Mask" "F.Paste")
			(net "FP_PWR_BTN_R_N")
		)
	)
	(footprint ""
		(layer "F.Cu")
		(at 261.747 -23.241 180)
		(property "Reference" "C5F2"
			(at 0 0 180)
			(layer "F.SilkS")
			(hide yes)
			(effects
				(font
					(size 1.27 1.27)
				)
			)
		)
		(property "Value" ""
			(at 0 0 180)
			(layer "F.Fab")
			(effects
				(font
					(size 1.27 1.27)
				)
			)
		)
		(duplicate_pad_numbers_are_jumpers no)
		(fp_rect
			(start -0.500126 1.598422)
			(end 0.500126 -0.201422)
			(stroke
				(width 0)
				(type default)
			)
			(fill no)
			(layer "F.CrtYd")
		)
		(fp_line
			(start 0.500126 1.598422)
			(end -0.500126 1.598422)
			(stroke
				(width 0.1)
				(type default)
			)
			(layer "F.Fab")
		)
		(fp_line
			(start 0.500126 -0.201422)
			(end 0.500126 1.598422)
			(stroke
				(width 0.1)
				(type default)
			)
			(layer "F.Fab")
		)
		(fp_line
			(start -0.500126 1.598422)
			(end -0.500126 -0.201422)
			(stroke
				(width 0.1)
				(type default)
			)
			(layer "F.Fab")
		)
		(fp_line
			(start -0.500126 -0.201422)
			(end 0.500126 -0.201422)
			(stroke
				(width 0.1)
				(type default)
			)
			(layer "F.Fab")
		)
		(pad "1" smd rect
			(at 0 0 90)
			(size 0.889 0.9906)
			(layers "F.Cu" "F.Mask" "F.Paste")
			(net "PVDDQ_ABC")
		)
		(pad "2" smd rect
			(at 0 1.397 90)
			(size 0.889 0.9906)
			(layers "F.Cu" "F.Mask" "F.Paste")
			(net "GND")
		)
		(zone
			(layer "F.Cu")
			(hatch none 0.5)
			(connect_pads
				(clearance 0)
			)
			(min_thickness 0.25)
			(keepout
				(tracks not_allowed)
				(vias allowed)
				(pads allowed)
				(copperpour not_allowed)
				(footprints allowed)
			)
			(placement
				(enabled no)
				(sheetname "")
			)
			(fill
				(thermal_gap 0.5)
				(thermal_bridge_width 0.5)
				(island_removal_mode 0)
			)
			(polygon
				(pts
					(xy 262.2423 -24.1935) (xy 261.2517 -24.1935) (xy 261.2517 -23.6855) (xy 262.2423 -23.6855)
				)
			)
		)
		(zone
			(layer "F.Cu")
			(hatch none 0.5)
			(connect_pads
				(clearance 0)
			)
			(min_thickness 0.25)
			(keepout
				(tracks allowed)
				(vias not_allowed)
				(pads allowed)
				(copperpour not_allowed)
				(footprints allowed)
			)
			(placement
				(enabled no)
				(sheetname "")
			)
			(fill
				(thermal_gap 0.5)
				(thermal_bridge_width 0.5)
				(island_removal_mode 0)
			)
			(polygon
				(pts
					(xy 262.2423 -24.1935) (xy 261.2517 -24.1935) (xy 261.2517 -23.6855) (xy 262.2423 -23.6855)
				)
			)
		)
	)
	(footprint ""
		(layer "F.Cu")
		(at 322.7324 -35.052 -90)
		(property "Reference" "R6F2"
			(at 0 0 270)
			(layer "F.SilkS")
			(hide yes)
			(effects
				(font
					(size 1.27 1.27)
				)
			)
		)
		(property "Value" ""
			(at 0 0 270)
			(layer "F.Fab")
			(effects
				(font
					(size 1.27 1.27)
				)
			)
		)
		(duplicate_pad_numbers_are_jumpers no)
		(fp_poly
			(pts
				(xy -0.2794 -0.1016) (xy 0.2794 -0.1016) (xy 0.2794 0.9906) (xy -0.2794 0.9906)
			)
			(stroke
				(width 0)
				(type default)
			)
			(fill no)
			(layer "F.CrtYd")
		)
		(fp_line
			(start -0.2794 0.9906)
			(end 0.2794 0.9906)
			(stroke
				(width 0.1)
				(type default)
			)
			(layer "F.Fab")
		)
		(fp_line
			(start 0.2794 0.9906)
			(end 0.2794 -0.1016)
			(stroke
				(width 0.1)
				(type default)
			)
			(layer "F.Fab")
		)
		(fp_line
			(start -0.2794 -0.1016)
			(end -0.2794 0.9906)
			(stroke
				(width 0.1)
				(type default)
			)
			(layer "F.Fab")
		)
		(fp_line
			(start 0.2794 -0.1016)
			(end -0.2794 -0.1016)
			(stroke
				(width 0.1)
				(type default)
			)
			(layer "F.Fab")
		)
		(pad "1" smd rect
			(at 0 0 270)
			(size 0.508 0.508)
			(layers "F.Cu" "F.Mask" "F.Paste")
			(net "FM_ADR_COMPLETE_CPU1_N")
		)
		(pad "2" smd rect
			(at 0 0.889 270)
			(size 0.508 0.508)
			(layers "F.Cu" "F.Mask" "F.Paste")
			(net "FM_ADR_COMPLETE_KLM_N")
		)
		(zone
			(layer "F.Cu")
			(hatch none 0.5)
			(connect_pads
				(clearance 0)
			)
			(min_thickness 0.25)
			(keepout
				(tracks not_allowed)
				(vias allowed)
				(pads allowed)
				(copperpour not_allowed)
				(footprints allowed)
			)
			(placement
				(enabled no)
				(sheetname "")
			)
			(fill
				(thermal_gap 0.5)
				(thermal_bridge_width 0.5)
				(island_removal_mode 0)
			)
			(polygon
				(pts
					(xy 322.0974 -35.306) (xy 322.0974 -34.798) (xy 322.4784 -34.798) (xy 322.4784 -35.306)
				)
			)
		)
		(zone
			(layer "F.Cu")
			(hatch none 0.5)
			(connect_pads
				(clearance 0)
			)
			(min_thickness 0.25)
			(keepout
				(tracks allowed)
				(vias not_allowed)
				(pads allowed)
				(copperpour not_allowed)
				(footprints allowed)
			)
			(placement
				(enabled no)
				(sheetname "")
			)
			(fill
				(thermal_gap 0.5)
				(thermal_bridge_width 0.5)
				(island_removal_mode 0)
			)
			(polygon
				(pts
					(xy 322.4784 -35.306) (xy 322.4784 -34.798) (xy 322.0974 -34.798) (xy 322.0974 -35.306)
				)
			)
		)
	)
	(footprint ""
		(layer "F.Cu")
		(at 5.6388 -142.875 -90)
		(property "Reference" "RT7"
			(at 0 0 270)
			(layer "F.SilkS")
			(hide yes)
			(effects
				(font
					(size 1.27 1.27)
				)
			)
		)
		(property "Value" "*"
			(at -0.0254 -2.6289 270)
			(unlocked yes)
			(layer "F.Fab")
			(hide yes)
			(effects
				(font
					(size 1.27 1.016)
					(thickness 0.1524)
				)
			)
		)
		(property "Device Type" "1R3F-GP_RCL_GP-1R3F-GP,64.1R00A"
			(at -0.0254 -4.1529 270)
			(unlocked yes)
			(layer "F.Fab")
			(hide yes)
			(effects
				(font
					(size 1.27 1.016)
					(thickness 0.1524)
				)
			)
		)
		(duplicate_pad_numbers_are_jumpers no)
		(fp_line
			(start -0.4826 0)
			(end -0.2032 0)
			(stroke
				(width 0.2032)
				(type default)
			)
			(layer "F.SilkS")
		)
		(fp_line
			(start 0.2032 0)
			(end 0.4826 0)
			(stroke
				(width 0.2032)
				(type default)
			)
			(layer "F.SilkS")
		)
		(fp_rect
			(start -0.5842 1.3335)
			(end 0.5842 -1.3335)
			(stroke
				(width 0)
				(type default)
			)
			(fill no)
			(layer "F.CrtYd")
		)
		(fp_rect
			(start -0.5842 1.3335)
			(end 0.5842 -1.3335)
			(stroke
				(width 0)
				(type default)
			)
			(fill no)
			(layer "F.Fab")
		)
		(pad "1" smd custom
			(at 0 -0.762 270)
			(size 0.2159 0.2159)
			(layers "F.Cu" "F.Mask" "F.Paste")
			(net "VR_PVDDQ_KLM_PH2_RC")
			(options
				(clearance outline)
				(anchor circle)
			)
			(primitives
				(gr_poly
					(pts
						(arc
							(start -0.3302 -0.4318)
							(mid -0.402042 -0.402042)
							(end -0.4318 -0.3302)
						)
						(arc
							(start -0.4318 0.3302)
							(mid -0.402042 0.402042)
							(end -0.3302 0.4318)
						)
						(arc
							(start 0.3302 0.4318)
							(mid 0.402042 0.402042)
							(end 0.4318 0.3302)
						)
						(arc
							(start 0.4318 -0.3302)
							(mid 0.402042 -0.402042)
							(end 0.3302 -0.4318)
						)
					)
					(width 0)
					(fill yes)
				)
			)
		)
		(pad "2" smd custom
			(at 0 0.762 270)
			(size 0.2159 0.2159)
			(layers "F.Cu" "F.Mask" "F.Paste")
			(net "GND")
			(options
				(clearance outline)
				(anchor circle)
			)
			(primitives
				(gr_poly
					(pts
						(arc
							(start -0.3302 -0.4318)
							(mid -0.402042 -0.402042)
							(end -0.4318 -0.3302)
						)
						(arc
							(start -0.4318 0.3302)
							(mid -0.402042 0.402042)
							(end -0.3302 0.4318)
						)
						(arc
							(start 0.3302 0.4318)
							(mid 0.402042 0.402042)
							(end 0.4318 0.3302)
						)
						(arc
							(start 0.4318 -0.3302)
							(mid 0.402042 -0.402042)
							(end 0.3302 -0.4318)
						)
					)
					(width 0)
					(fill yes)
				)
			)
		)
	)
	(footprint ""
		(layer "F.Cu")
		(at 16.764 -69.977 -90)
		(property "Reference" "R1D45"
			(at 0 0 270)
			(layer "F.SilkS")
			(hide yes)
			(effects
				(font
					(size 1.27 1.27)
				)
			)
		)
		(property "Value" ""
			(at 0 0 270)
			(layer "F.Fab")
			(effects
				(font
					(size 1.27 1.27)
				)
			)
		)
		(duplicate_pad_numbers_are_jumpers no)
		(fp_rect
			(start -0.2794 0.9906)
			(end 0.2794 -0.1016)
			(stroke
				(width 0)
				(type default)
			)
			(fill no)
			(layer "F.CrtYd")
		)
		(fp_line
			(start -0.2794 0.9906)
			(end 0.2794 0.9906)
			(stroke
				(width 0.1)
				(type default)
			)
			(layer "F.Fab")
		)
		(fp_line
			(start 0.2794 0.9906)
			(end 0.2794 -0.1016)
			(stroke
				(width 0.1)
				(type default)
			)
			(layer "F.Fab")
		)
		(fp_line
			(start -0.2794 -0.1016)
			(end -0.2794 0.9906)
			(stroke
				(width 0.1)
				(type default)
			)
			(layer "F.Fab")
		)
		(fp_line
			(start 0.2794 -0.1016)
			(end -0.2794 -0.1016)
			(stroke
				(width 0.1)
				(type default)
			)
			(layer "F.Fab")
		)
		(pad "1" smd rect
			(at 0 0 270)
			(size 0.508 0.508)
			(layers "F.Cu" "F.Mask" "F.Paste")
			(net "A_HSC_MON")
		)
		(pad "2" smd rect
			(at 0 0.889 270)
			(size 0.508 0.508)
			(layers "F.Cu" "F.Mask" "F.Paste")
			(net "A_HSC_HSN")
		)
		(zone
			(layer "F.Cu")
			(hatch none 0.5)
			(connect_pads
				(clearance 0)
			)
			(min_thickness 0.25)
			(keepout
				(tracks not_allowed)
				(vias allowed)
				(pads allowed)
				(copperpour not_allowed)
				(footprints allowed)
			)
			(placement
				(enabled no)
				(sheetname "")
			)
			(fill
				(thermal_gap 0.5)
				(thermal_bridge_width 0.5)
				(island_removal_mode 0)
			)
			(polygon
				(pts
					(xy 16.129 -70.231) (xy 16.129 -69.723) (xy 16.51 -69.723) (xy 16.51 -70.231)
				)
			)
		)
		(zone
			(layer "F.Cu")
			(hatch none 0.5)
			(connect_pads
				(clearance 0)
			)
			(min_thickness 0.25)
			(keepout
				(tracks allowed)
				(vias not_allowed)
				(pads allowed)
				(copperpour not_allowed)
				(footprints allowed)
			)
			(placement
				(enabled no)
				(sheetname "")
			)
			(fill
				(thermal_gap 0.5)
				(thermal_bridge_width 0.5)
				(island_removal_mode 0)
			)
			(polygon
				(pts
					(xy 16.129 -70.231) (xy 16.129 -69.723) (xy 16.51 -69.723) (xy 16.51 -70.231)
				)
			)
		)
	)
	(footprint ""
		(layer "F.Cu")
		(at 173.9265 -67.056 90)
		(property "Reference" "R4D57"
			(at 0 0 90)
			(layer "F.SilkS")
			(hide yes)
			(effects
				(font
					(size 1.27 1.27)
				)
			)
		)
		(property "Value" ""
			(at 0 0 90)
			(layer "F.Fab")
			(effects
				(font
					(size 1.27 1.27)
				)
			)
		)
		(duplicate_pad_numbers_are_jumpers no)
		(fp_poly
			(pts
				(xy -0.2794 -0.1016) (xy 0.2794 -0.1016) (xy 0.2794 0.9906) (xy -0.2794 0.9906)
			)
			(stroke
				(width 0)
				(type default)
			)
			(fill no)
			(layer "F.CrtYd")
		)
		(fp_line
			(start 0.2794 -0.1016)
			(end -0.2794 -0.1016)
			(stroke
				(width 0.1)
				(type default)
			)
			(layer "F.Fab")
		)
		(fp_line
			(start -0.2794 -0.1016)
			(end -0.2794 0.9906)
			(stroke
				(width 0.1)
				(type default)
			)
			(layer "F.Fab")
		)
		(fp_line
			(start 0.2794 0.9906)
			(end 0.2794 -0.1016)
			(stroke
				(width 0.1)
				(type default)
			)
			(layer "F.Fab")
		)
		(fp_line
			(start -0.2794 0.9906)
			(end 0.2794 0.9906)
			(stroke
				(width 0.1)
				(type default)
			)
			(layer "F.Fab")
		)
		(pad "1" smd rect
			(at 0 0 90)
			(size 0.508 0.508)
			(layers "F.Cu" "F.Mask" "F.Paste")
			(net "VR_PVCCIO_CPU1_VINSEN")
		)
		(pad "2" smd rect
			(at 0 0.889 90)
			(size 0.508 0.508)
			(layers "F.Cu" "F.Mask" "F.Paste")
			(net "GND")
		)
		(zone
			(layer "F.Cu")
			(hatch none 0.5)
			(connect_pads
				(clearance 0)
			)
			(min_thickness 0.25)
			(keepout
				(tracks allowed)
				(vias not_allowed)
				(pads allowed)
				(copperpour not_allowed)
				(footprints allowed)
			)
			(placement
				(enabled no)
				(sheetname "")
			)
			(fill
				(thermal_gap 0.5)
				(thermal_bridge_width 0.5)
				(island_removal_mode 0)
			)
			(polygon
				(pts
					(xy 174.1805 -66.802) (xy 174.1805 -67.31) (xy 174.5615 -67.31) (xy 174.5615 -66.802)
				)
			)
		)
		(zone
			(layer "F.Cu")
			(hatch none 0.5)
			(connect_pads
				(clearance 0)
			)
			(min_thickness 0.25)
			(keepout
				(tracks not_allowed)
				(vias allowed)
				(pads allowed)
				(copperpour not_allowed)
				(footprints allowed)
			)
			(placement
				(enabled no)
				(sheetname "")
			)
			(fill
				(thermal_gap 0.5)
				(thermal_bridge_width 0.5)
				(island_removal_mode 0)
			)
			(polygon
				(pts
					(xy 174.5615 -66.802) (xy 174.5615 -67.31) (xy 174.1805 -67.31) (xy 174.1805 -66.802)
				)
			)
		)
	)
	(footprint ""
		(layer "F.Cu")
		(at 204.089 -105.918 90)
		(property "Reference" "R6N1"
			(at 0 0 90)
			(layer "F.SilkS")
			(hide yes)
			(effects
				(font
					(size 1.27 1.27)
				)
			)
		)
		(property "Value" ""
			(at 0 0 90)
			(layer "F.Fab")
			(effects
				(font
					(size 1.27 1.27)
				)
			)
		)
		(duplicate_pad_numbers_are_jumpers no)
		(fp_poly
			(pts
				(xy -0.2794 -0.1016) (xy 0.2794 -0.1016) (xy 0.2794 0.9906) (xy -0.2794 0.9906)
			)
			(stroke
				(width 0)
				(type default)
			)
			(fill no)
			(layer "F.CrtYd")
		)
		(fp_line
			(start 0.2794 -0.1016)
			(end -0.2794 -0.1016)
			(stroke
				(width 0.1)
				(type default)
			)
			(layer "F.Fab")
		)
		(fp_line
			(start -0.2794 -0.1016)
			(end -0.2794 0.9906)
			(stroke
				(width 0.1)
				(type default)
			)
			(layer "F.Fab")
		)
		(fp_line
			(start 0.2794 0.9906)
			(end 0.2794 -0.1016)
			(stroke
				(width 0.1)
				(type default)
			)
			(layer "F.Fab")
		)
		(fp_line
			(start -0.2794 0.9906)
			(end 0.2794 0.9906)
			(stroke
				(width 0.1)
				(type default)
			)
			(layer "F.Fab")
		)
		(pad "1" smd rect
			(at 0 0 90)
			(size 0.508 0.508)
			(layers "F.Cu" "F.Mask" "F.Paste")
			(net "SVID_ALERT0_CPU0_R_N")
		)
		(pad "2" smd rect
			(at 0 0.889 90)
			(size 0.508 0.508)
			(layers "F.Cu" "F.Mask" "F.Paste")
			(net "PVCCIO_CPU0")
		)
		(zone
			(layer "F.Cu")
			(hatch none 0.5)
			(connect_pads
				(clearance 0)
			)
			(min_thickness 0.25)
			(keepout
				(tracks allowed)
				(vias not_allowed)
				(pads allowed)
				(copperpour not_allowed)
				(footprints allowed)
			)
			(placement
				(enabled no)
				(sheetname "")
			)
			(fill
				(thermal_gap 0.5)
				(thermal_bridge_width 0.5)
				(island_removal_mode 0)
			)
			(polygon
				(pts
					(xy 204.343 -105.664) (xy 204.343 -106.172) (xy 204.724 -106.172) (xy 204.724 -105.664)
				)
			)
		)
		(zone
			(layer "F.Cu")
			(hatch none 0.5)
			(connect_pads
				(clearance 0)
			)
			(min_thickness 0.25)
			(keepout
				(tracks not_allowed)
				(vias allowed)
				(pads allowed)
				(copperpour not_allowed)
				(footprints allowed)
			)
			(placement
				(enabled no)
				(sheetname "")
			)
			(fill
				(thermal_gap 0.5)
				(thermal_bridge_width 0.5)
				(island_removal_mode 0)
			)
			(polygon
				(pts
					(xy 204.724 -105.664) (xy 204.724 -106.172) (xy 204.343 -106.172) (xy 204.343 -105.664)
				)
			)
		)
	)
)
